FILE_TYPE = CONNECTIVITY;
{Allegro Design Entry HDL 16.6-p007 (v16-6-112F) 10/10/2012}
"PAGE_NUMBER" = 222;
0"NC";
1"GND\g";
2"GND\g";
3"GND\g";
4"GND\g";
5"GND\g";
6"GND\g";
7"GND\g";
8"PVDDQ_DEF\g";
9"GND\g";
10"P3V3\g";
11"P3V3\g";
12"GND\g";
13"PVTT_DEF\g";
14"GND\g";
15"PVTT_DEF\g";
16"PWRGD_PVTT_CPU0";
17"PWRGD_PVTT_DEF_CPU0_R";
18"VR_PVTT_DEF_SNS";
19"VR_PVTT_DEF_VREF";
20"VR_PVTT_DEF_BIAS";
21"VSENSE_PVDDQ_DEF_VTT";
22"FM_PVTT_DEF_EN_R";
23"PWRGD_PVDDQ_DEF";
%"CAP"
"1","(4000,1725)","0","mstr_discrete","I12";
;
CDS_SEC"1"
BOM_COST"MEM_VRD_VTT_DEF"
SEC"1"
SEC_TYPE"0402LF"
ROOM"VTT_DEF_PWR_VR"
CDS_LOCATION"C4A12"
CDS_LIB"mstr_discrete"
MATERIAL"X7R"
VOLTAGE"50V"
PACK_TYPE"0402LF"
TOLERANCE"10%"
VALUE"1000PF"
PART_NUMBER"A36096-046"
LOCATION"C4A12";
"A"
$PN"1"17;
"B"
$PN"2"1;
%"GND"
"1","(4000,1475)","0","mstr_symbols","I13";
;
HDL_POWER"GND"
BODY_TYPE"PLUMBING"
CDS_LIB"mstr_symbols"
SIZE"1B"
VOLTAGE"0.0V";
"A\NAC"1;
%"CAP"
"1","(4125,1125)","0","mstr_discrete","I16";
;
CDS_SEC"1"
SEC"1"
BOM_COST"MEM_VRD_VTT_DEF"
SEC_TYPE"0805LF"
ROOM"VTT_DEF_PWR_VR"
CDS_LOCATION"C4A1"
CDS_LIB"mstr_discrete"
MATERIAL"X6S"
VOLTAGE"4V"
TOLERANCE"20%"
VALUE"22UF"
LOCATION"C4A1"
PACK_TYPE"0805LF"
PART_NUMBER"C95333-002";
"A"
$PN"1"15;
"B"
$PN"2"2;
%"GND"
"1","(4125,725)","0","mstr_symbols","I17";
;
HDL_POWER"GND"
CDS_LIB"mstr_symbols"
SIZE"1B"
BODY_TYPE"PLUMBING"
VOLTAGE"0.0V";
"A\NAC"2;
%"RES"
"2","(3575,2100)","0","mstr_discrete","I19";
;
CDS_SEC"1"
ROOM"VTT_DEF_PWR_VR"
CDS_LOCATION"R6L9"
SEC"1"
SEC_TYPE"0402"
BOM_COST"MEM_VRD_VTT_DEF"
CDS_LIB"mstr_discrete"
WATTAGE"1/16W"
TOLERANCE"1%"
VALUE"10.0K"
LOCATION"R6L9"
MATERIAL"CHIP"
PART_NUMBER"G21796-016"
PACK_TYPE"0402";
"A"
$PN"1"11;
"B"
$PN"2"17;
%"CAP"
"1","(2550,950)","0","mstr_discrete","I21";
;
CDS_SEC"1"
CDS_LOCATION"C4A9"
ROOM"VTT_DEF_PWR_VR"
SEC_TYPE"0402"
BOM_COST"MEM_VRD_VTT_DEF"
SEC"1"
CDS_LIB"mstr_discrete"
LOCATION"C4A9"
VOLTAGE"16V"
VALUE"1.0UF"
MATERIAL"X6S"
PACK_TYPE"0402"
TOLERANCE"10%"
PART_NUMBER"D97712-011";
"A"
$PN"1"19;
"B"
$PN"2"3;
%"GND"
"1","(2550,675)","0","mstr_symbols","I22";
;
SIZE"1B"
HDL_POWER"GND"
BODY_TYPE"PLUMBING"
CDS_LIB"mstr_symbols"
VOLTAGE"0.0V";
"A\NAC"3;
%"GND"
"1","(2150,675)","0","mstr_symbols","I23";
;
HDL_POWER"GND"
VOLTAGE"0.0V"
SIZE"1B"
CDS_LIB"mstr_symbols"
BODY_TYPE"PLUMBING";
"A\NAC"4;
%"CAP"
"1","(600,2475)","0","mstr_discrete","I24";
;
CDS_SEC"1"
SEC_TYPE"0603LF"
BOM_COST"MEM_VRD_VTT_DEF"
SEC"1"
CDS_LOCATION"C6L3"
ROOM"VTT_DEF_PWR_VR"
CDS_LIB"mstr_discrete"
LOCATION"C6L3"
PACK_TYPE"0603LF"
PART_NUMBER"E15431-001"
MATERIAL"X6S"
VOLTAGE"4V"
TOLERANCE"20%"
VALUE"10UF";
"A"
$PN"1"8;
"B"
$PN"2"5;
%"GND"
"1","(600,2200)","0","mstr_symbols","I25";
;
HDL_POWER"GND"
BODY_TYPE"PLUMBING"
SIZE"1B"
CDS_LIB"mstr_symbols"
VOLTAGE"0.0V"
BOM_COST"MEM_VRD_VTT_DEF"
ROOM"VTT_DEF_PWR_VR";
"A\NAC"5;
%"CAP"
"1","(175,2450)","0","mstr_discrete","I26";
;
CDS_SEC"1"
ROOM"VTT_DEF_PWR_VR"
SEC"1"
BOM_COST"MEM_VRD_VTT_DEF"
SEC_TYPE"0603LF"
CDS_LOCATION"C6L4"
CDS_LIB"mstr_discrete"
PART_NUMBER"E15431-001"
LOCATION"C6L4"
MATERIAL"X6S"
VOLTAGE"4V"
PACK_TYPE"0603LF"
TOLERANCE"20%"
VALUE"10UF";
"A"
$PN"1"8;
"B"
$PN"2"6;
%"GND"
"1","(175,2200)","0","mstr_symbols","I27";
;
HDL_POWER"GND"
BODY_TYPE"PLUMBING"
CDS_LIB"mstr_symbols"
SIZE"1B"
VOLTAGE"0.0V"
ROOM"VTT_DEF_PWR_VR"
BOM_COST"MEM_VRD_VTT_DEF";
"A\NAC"6;
%"CAP"
"1","(600,1600)","0","mstr_discrete","I28";
;
CDS_SEC"1"
SEC"1"
SEC_TYPE"0402"
BOM_COST"MEM_VRD_VTT_DEF"
ROOM"VTT_DEF_PWR_VR"
CDS_LIB"mstr_discrete"
CDS_LOCATION"C4A10"
VOLTAGE"16V"
MATERIAL"X6S"
LOCATION"C4A10"
PART_NUMBER"D97712-011"
VALUE"1.0UF"
TOLERANCE"10%"
PACK_TYPE"0402";
"A"
$PN"1"20;
"B"
$PN"2"7;
%"GND"
"1","(600,1350)","0","mstr_symbols","I29";
;
HDL_POWER"GND"
SIZE"1B"
VOLTAGE"0.0V"
CDS_LIB"mstr_symbols"
BODY_TYPE"PLUMBING";
"A\NAC"7;
%"RES"
"1","(275,1850)","0","mstr_discrete","I30";
;
CDS_SEC"1"
SEC"1"
SEC_TYPE"0402"
CDS_LIB"mstr_discrete"
CDS_LOCATION"R6L11"
BOM_COST"MEM_VRD_VTT_DEF"
ROOM"VTT_DEF_PWR_VR"
MATERIAL"CHIP"
TOLERANCE"5%"
PACK_TYPE"0402"
LOCATION"R6L11"
PART_NUMBER"G21497-005"
WATTAGE"1/16W"
VALUE"0.0";
"B"
$PN"2"20;
"A"
$PN"1"10;
%"MIC5166"
"1","(1700,1150)","0","mstr_vreg","I31";
;
CDS_SEC"1"
CDS_LIB"mstr_vreg"
CDS_LMAN_SYM_OUTLINE"-250,350,250,-350"
ROOM"VTT_DEF_PWR_VR"
CDS_LOCATION"EU4A1"
SEC"1"
SEC_TYPE"DFN"
PACK_TYPE"DFN"
BOM_COST"MEM_VRD_VTT_DEF"
LOCATION"EU4A1"
MATERIAL"IC"
PART_NUMBER"H55101-001";
"THPAD"
$PN"11"4;
"VTT"
$PN"9"15;
"PGND"
$PN"8"4;
"SNS"
$PN"6"18;
"VDDQ"
$PN"4"21;
"PG"
$PN"5"17;
"AGND"
$PN"3"4;
"BIAS"
$PN"2"20;
"VREF"
$PN"1"19;
"VIN"
$PN"10"8;
"EN"
$PN"7"22;
%"RES"
"2","(-575,1650)","1","mstr_discrete","I34";
;
CDS_SEC"1"
BOM_COST"MEM_VRD_VTT_DEF"
ROOM"VTT_DEF_PWR_VR"
SEC"1"
NO_XNET_CONNECTION"1"
SEC_TYPE"0402"
CDS_LOCATION"R6L10"
CDS_LIB"mstr_discrete"
MATERIAL"CHIP"
PACK_TYPE"0402"
WATTAGE"1/16W"
PART_NUMBER"G21497-005"
LOCATION"R6L10"
VALUE"0.0"
TOLERANCE"5%";
"A"
$PN"1"8;
"B"
$PN"2"21;
%"PVDDQ_DEF"
"1","(-1300,2875)","0","mstr_symbols","I35";
;
HDL_POWER"PVDDQ_DEF"
BODY_TYPE"PLUMBING"
CDS_LIB"mstr_symbols"
VOLTAGE"1.2V";
"G\NAC"8;
%"RES"
"2","(-175,750)","2","mstr_discrete","I37";
;
CDS_SEC"1"
ROOM"VTT_DEF_PWR_VR"
SEC"1"
SEC_TYPE"0402"
BOM_COST"MEM_VRD_VTT_DEF"
CDS_LOCATION"R6L4"
CDS_LIB"mstr_discrete"
WATTAGE"1/16W"
PACK_TYPE"0402"
TOLERANCE"1%"
VALUE"1.0M"
PART_NUMBER"G21796-021"
LOCATION"R6L4"
MATERIAL"EMPTY";
"A"
$PN"1"10;
"B"
$PN"2"22;
%"RES"
"1","(-375,225)","0","mstr_discrete","I38";
;
CDS_SEC"1"
SEC_TYPE"0402"
BOM_COST"MEM_VRD_VTT_DEF"
ROOM"VTT_DEF_PWR_VR"
CDS_LOCATION"R4A2"
SEC"1"
CDS_LIB"mstr_discrete"
LOCATION"R4A2"
TOLERANCE"5%"
PACK_TYPE"0402"
VALUE"0.0"
PART_NUMBER"G21497-005"
WATTAGE"1/16W"
MATERIAL"CHIP";
"B"
$PN"2"22;
"A"
$PN"1"23;
%"GND"
"1","(-225,-525)","0","mstr_symbols","I39";
;
HDL_POWER"GND"
CDS_LIB"mstr_symbols"
BODY_TYPE"PLUMBING"
SIZE"1B"
VOLTAGE"0.0V";
"A\NAC"9;
%"CAP"
"1","(-225,-300)","2","mstr_discrete","I40";
;
CDS_SEC"1"
SEC"1"
SEC_TYPE"0402LF"
CDS_LIB"mstr_discrete"
ROOM"VTT_DEF_PWR_VR"
CDS_LOCATION"C4A2"
BOM_COST"MEM_VRD_VTT_DEF"
PART_NUMBER"A36096-046"
VALUE"1000PF"
LOCATION"C4A2"
VOLTAGE"50V"
TOLERANCE"10%"
PACK_TYPE"0402LF"
MATERIAL"EMPTY";
"A"
$PN"1"22;
"B"
$PN"2"9;
%"P3V3"
"1","(-450,2250)","0","mstr_symbols","I42";
;
BODY_TYPE"PLUMBING"
CDS_LIB"mstr_symbols"
SIZE"1B"
VOLTAGE"3.3V"
HDL_POWER"P3V3";
"G\NAC"10;
%"P3V3"
"1","(3575,2425)","0","mstr_symbols","I43";
;
SIZE"1B"
VOLTAGE"3.3V"
CDS_LIB"mstr_symbols"
BODY_TYPE"PLUMBING"
HDL_POWER"P3V3";
"G\NAC"11;
%"GND"
"1","(425,875)","0","mstr_symbols","I45";
;
HDL_POWER"GND"
SIZE"1B"
CDS_LIB"mstr_symbols"
VOLTAGE"0.0V"
BODY_TYPE"PLUMBING";
"A\NAC"12;
%"CAP"
"1","(425,1075)","0","mstr_discrete","I46";
;
CDS_SEC"1"
ROOM"VTT_DEF_PWR_VR"
SEC"1"
SEC_TYPE"0603"
CDS_LOCATION"C4A11"
CDS_LIB"mstr_discrete"
VOLTAGE"6.3V"
TOLERANCE"10%"
VALUE"4.7UF"
LOCATION"C4A11"
PART_NUMBER"E15431-003"
PACK_TYPE"0603"
MATERIAL"X6S";
"A"
$PN"1"21;
"B"
$PN"2"12;
%"CAP_A"
"1","(3675,3475)","0","dev_discrete","I47";
;
SEC"1"
SEC_TYPE"0603V"
CDS_SEC"1"
CDS_LOCATION"C5L4"
CDS_LIB"dev_discrete"
LOCATION"C5L4"
PACK_TYPE"0603V"
VALUE"47UF"
PART_NUMBER"602433-106"
TOLERANCE"20%"
VOLTAGE"4V"
MATERIAL"X5R";
"B"
$PN"2"14;
"A"
$PN"1"13;
%"CAP_A"
"1","(4025,3475)","0","dev_discrete","I48";
;
SEC"1"
CDS_SEC"1"
SEC_TYPE"0603V"
CDS_LOCATION"C5M13"
CDS_LIB"dev_discrete"
MATERIAL"X5R"
VOLTAGE"4V"
PACK_TYPE"0603V"
TOLERANCE"20%"
VALUE"47UF"
PART_NUMBER"602433-106"
LOCATION"C5M13";
"B"
$PN"2"14;
"A"
$PN"1"13;
%"CAP_A"
"1","(4425,3475)","0","dev_discrete","I49";
;
SEC"1"
SEC_TYPE"0603V"
CDS_SEC"1"
CDS_LOCATION"C5L5"
CDS_LIB"dev_discrete"
PACK_TYPE"0603V"
PART_NUMBER"602433-106"
LOCATION"C5L5"
MATERIAL"X5R"
VOLTAGE"4V"
TOLERANCE"20%"
VALUE"47UF";
"B"
$PN"2"14;
"A"
$PN"1"13;
%"RES"
"1","(4400,1925)","0","mstr_discrete","I51";
;
CDS_SEC"1"
SEC"1"
SEC_TYPE"0402"
CDS_LIB"mstr_discrete"
CDS_LOCATION"R4A6"
PART_NUMBER"G21796-074"
PACK_TYPE"0402"
TOLERANCE"1%"
MATERIAL"CHIP"
LOCATION"R4A6"
VALUE"33.2"
WATTAGE"1/16W";
"B"
$PN"2"16;
"A"
$PN"1"17;
%"RES"
"1","(5025,1125)","1","mstr_discrete","I52";
;
$SEC"1"
CDS_SEC"1"
CDS_LIB"mstr_discrete"
CDS_LOCATION"R4A1"
MATERIAL"CHIP"
PACK_TYPE"0402"
WATTAGE"1/16W"
TOLERANCE"1.0%"
VALUE"51.1"
PART_NUMBER"G21796-208"
LOCATION"R4A1";
"B"
$PN"2"15;
"A"
$PN"1"2;
%"SHUNT"
"1","(5100,125)","0","mstr_misc","I53";
;
CDS_SEC"1"
CDS_LOCATION"SH5L1"
SEC_TYPE"SH0201"
SEC"1"
CDS_LIB"mstr_misc"
MATERIAL"EMPTY"
PIN_SHORT"A:B"
PACK_TYPE"SH0201"
LOCATION"SH5L1"
PART_NUMBER"N_A";
"A"
$PN"1"18;
"B"
$PN"2"15;
%"PVTT_DEF"
"1","(3675,3750)","0","mstr_symbols","I6";
;
ROOM"VTT_DEF_PWR_VR"
BOM_COST"MEM_VRD_PVDDQ_AB"
HDL_POWER"PVTT_DEF"
CDS_LIB"mstr_symbols"
BODY_TYPE"PLUMBING"
VOLTAGE"0.6V";
"G\NAC"13;
%"GND"
"1","(4525,3075)","0","mstr_symbols","I8";
;
CDS_LIB"mstr_symbols"
HDL_POWER"GND"
BOM_COST"MEM_VRD_PVDDQ_AB"
BODY_TYPE"PLUMBING"
SIZE"1B"
VOLTAGE"0.0V"
ROOM"VTT_DEF_PWR_VR";
"A\NAC"14;
%"PVTT_DEF"
"1","(5675,1675)","0","mstr_symbols","I9";
;
CDS_LIB"mstr_symbols"
HDL_POWER"PVTT_DEF"
BODY_TYPE"PLUMBING"
VOLTAGE"0.6V";
"G\NAC"15;
END.
